# SCM (Grand Teton) — schematic netlist excerpt (pin names and nets, part order shuffled) for the footprints in the layout excerpt that follows; sources: Cadence DE-HDL packaged netlist, KiCad conversion of 12092022_DA0F0TMDCD0_F0T_Management_Board_D_brd_V3_OCP.brd

R707  Q_RES  0 5% CHIP  pkg 0402LF  page 29 : A = FM_DEBUG_PORT_R_PRSNT_N ; B = FM_DEBUG_PORT_PRSNT_N
R828  Q_RES  4.7K 1% EMPTY  pkg 0402LF  page 11 : A = P3V3_AUX ; B = RST_ROT_CPU_N

(kicad_pcb
	(version 20260206)
	(generator "pcbnew")
	(generator_version "10.0")
	(general
		(thickness 1.6)
		(legacy_teardrops no)
	)
	(paper "A4")
	(title_block
		(title "12092022_DA0F0TMDCD0_F0T_Management_Board_D_brd_V3_OCP.brd")
		(comment 1 "Grand Teton / footprints 1153-1154 of 1440")
	)
	(layers
		(0 "F.Cu" signal "TOP")
		(4 "In1.Cu" signal "GND")
		(6 "In2.Cu" signal "IN1")
		(8 "In3.Cu" signal "GND1")
		(10 "In4.Cu" signal "IN2")
		(12 "In5.Cu" signal "VCC")
		(14 "In6.Cu" signal "VCC1")
		(16 "In7.Cu" signal "IN3")
		(18 "In8.Cu" signal "GND2")
		(20 "In9.Cu" signal "IN4")
		(22 "In10.Cu" signal "GND3")
		(2 "B.Cu" signal "BOTTOM")
		(9 "F.Adhes" user "F.Adhesive")
		(11 "B.Adhes" user "B.Adhesive")
		(13 "F.Paste" user "Package Geometry/Pastemask Top")
		(15 "B.Paste" user "Package Geometry/Pastemask Bottom")
		(5 "F.SilkS" user "Ref Des/Silkscreen Top")
		(7 "B.SilkS" user "Ref Des/Silkscreen Bottom")
		(1 "F.Mask" user "Board Geometry/Soldermask Top")
		(3 "B.Mask" user "Board Geometry/Soldermask Bottom")
		(17 "Dwgs.User" user "User.Drawings")
		(19 "Cmts.User" user "User.Comments")
		(21 "Eco1.User" user "User.Eco1")
		(23 "Eco2.User" user "User.Eco2")
		(25 "Edge.Cuts" user "Board Geometry/Outline")
		(27 "Margin" user)
		(31 "F.CrtYd" user "Package Geometry/Place Bound Top")
		(29 "B.CrtYd" user "Package Geometry/Place Bound Bottom")
		(35 "F.Fab" user "Ref Des/Assembly Top")
		(33 "B.Fab" user "Ref Des/Assembly Bottom")
	)
	(footprint ""
		(layer "B.Cu")
		(at 56.261 -16.764 90)
		(property "Reference" "R707"
			(at 0 0 90)
			(layer "B.SilkS")
			(hide yes)
			(effects
				(font
					(size 1.27 1.27)
				)
				(justify mirror)
			)
		)
		(property "Value" ""
			(at 0 0 90)
			(layer "B.Fab")
			(effects
				(font
					(size 1.27 1.27)
				)
				(justify mirror)
			)
		)
		(duplicate_pad_numbers_are_jumpers no)
		(fp_line
			(start 0.7874 -0.4064)
			(end -0.7874 -0.4064)
			(stroke
				(width 0.1524)
				(type default)
			)
			(layer "B.SilkS")
		)
		(fp_line
			(start -0.7874 -0.4064)
			(end -0.7874 0.4064)
			(stroke
				(width 0.1524)
				(type default)
			)
			(layer "B.SilkS")
		)
		(fp_line
			(start 0.7874 0.4064)
			(end 0.7874 -0.4064)
			(stroke
				(width 0.1524)
				(type default)
			)
			(layer "B.SilkS")
		)
		(fp_line
			(start -0.7874 0.4064)
			(end 0.7874 0.4064)
			(stroke
				(width 0.1524)
				(type default)
			)
			(layer "B.SilkS")
		)
		(fp_line
			(start 0.67945 -0.305054)
			(end 0.12065 -0.305054)
			(stroke
				(width 0.1)
				(type default)
			)
			(layer "B.Fab")
		)
		(fp_line
			(start 0.12065 -0.305054)
			(end 0.12065 -0.2794)
			(stroke
				(width 0.1)
				(type default)
			)
			(layer "B.Fab")
		)
		(fp_line
			(start -0.12065 -0.3048)
			(end -0.67945 -0.3048)
			(stroke
				(width 0.1)
				(type default)
			)
			(layer "B.Fab")
		)
		(fp_line
			(start -0.67945 -0.3048)
			(end -0.67945 0.3048)
			(stroke
				(width 0.1)
				(type default)
			)
			(layer "B.Fab")
		)
		(fp_line
			(start 0.12065 -0.2794)
			(end -0.12065 -0.2794)
			(stroke
				(width 0.1)
				(type default)
			)
			(layer "B.Fab")
		)
		(fp_line
			(start -0.12065 -0.2794)
			(end -0.12065 -0.3048)
			(stroke
				(width 0.1)
				(type default)
			)
			(layer "B.Fab")
		)
		(fp_line
			(start 0.12065 0.2794)
			(end 0.12065 0.3048)
			(stroke
				(width 0.1)
				(type default)
			)
			(layer "B.Fab")
		)
		(fp_line
			(start -0.120396 0.2794)
			(end 0.12065 0.2794)
			(stroke
				(width 0.1)
				(type default)
			)
			(layer "B.Fab")
		)
		(fp_line
			(start 0.67945 0.3048)
			(end 0.67945 -0.305054)
			(stroke
				(width 0.1)
				(type default)
			)
			(layer "B.Fab")
		)
		(fp_line
			(start 0.12065 0.3048)
			(end 0.67945 0.3048)
			(stroke
				(width 0.1)
				(type default)
			)
			(layer "B.Fab")
		)
		(fp_line
			(start -0.120396 0.3048)
			(end -0.120396 0.2794)
			(stroke
				(width 0.1)
				(type default)
			)
			(layer "B.Fab")
		)
		(fp_line
			(start -0.67945 0.3048)
			(end -0.120396 0.3048)
			(stroke
				(width 0.1)
				(type default)
			)
			(layer "B.Fab")
		)
		(pad "1" smd circle
			(at 0.40005 0 270)
			(size 0 0)
			(layers "B.Cu" "B.Mask" "B.Paste")
			(net "FM_DEBUG_PORT_R_PRSNT_N")
		)
		(pad "2" smd circle
			(at -0.40005 0 270)
			(size 0 0)
			(layers "B.Cu" "B.Mask" "B.Paste")
			(net "FM_DEBUG_PORT_PRSNT_N")
		)
	)
	(footprint ""
		(layer "B.Cu")
		(at 22.5552 -106.5022 -90)
		(property "Reference" "R828"
			(at 0 0 90)
			(layer "B.SilkS")
			(hide yes)
			(effects
				(font
					(size 1.27 1.27)
				)
				(justify mirror)
			)
		)
		(property "Value" ""
			(at 0 0 90)
			(layer "B.Fab")
			(effects
				(font
					(size 1.27 1.27)
				)
				(justify mirror)
			)
		)
		(duplicate_pad_numbers_are_jumpers no)
		(fp_line
			(start -0.7874 0.4064)
			(end 0.7874 0.4064)
			(stroke
				(width 0.1524)
				(type default)
			)
			(layer "B.SilkS")
		)
		(fp_line
			(start 0.7874 0.4064)
			(end 0.7874 -0.4064)
			(stroke
				(width 0.1524)
				(type default)
			)
			(layer "B.SilkS")
		)
		(fp_line
			(start -0.7874 -0.4064)
			(end -0.7874 0.4064)
			(stroke
				(width 0.1524)
				(type default)
			)
			(layer "B.SilkS")
		)
		(fp_line
			(start 0.7874 -0.4064)
			(end -0.7874 -0.4064)
			(stroke
				(width 0.1524)
				(type default)
			)
			(layer "B.SilkS")
		)
		(fp_line
			(start -0.67945 0.3048)
			(end -0.120396 0.3048)
			(stroke
				(width 0.1)
				(type default)
			)
			(layer "B.Fab")
		)
		(fp_line
			(start -0.120396 0.3048)
			(end -0.120396 0.2794)
			(stroke
				(width 0.1)
				(type default)
			)
			(layer "B.Fab")
		)
		(fp_line
			(start 0.12065 0.3048)
			(end 0.67945 0.3048)
			(stroke
				(width 0.1)
				(type default)
			)
			(layer "B.Fab")
		)
		(fp_line
			(start 0.67945 0.3048)
			(end 0.67945 -0.305054)
			(stroke
				(width 0.1)
				(type default)
			)
			(layer "B.Fab")
		)
		(fp_line
			(start -0.120396 0.2794)
			(end 0.12065 0.2794)
			(stroke
				(width 0.1)
				(type default)
			)
			(layer "B.Fab")
		)
		(fp_line
			(start 0.12065 0.2794)
			(end 0.12065 0.3048)
			(stroke
				(width 0.1)
				(type default)
			)
			(layer "B.Fab")
		)
		(fp_line
			(start -0.12065 -0.2794)
			(end -0.12065 -0.3048)
			(stroke
				(width 0.1)
				(type default)
			)
			(layer "B.Fab")
		)
		(fp_line
			(start 0.12065 -0.2794)
			(end -0.12065 -0.2794)
			(stroke
				(width 0.1)
				(type default)
			)
			(layer "B.Fab")
		)
		(fp_line
			(start -0.67945 -0.3048)
			(end -0.67945 0.3048)
			(stroke
				(width 0.1)
				(type default)
			)
			(layer "B.Fab")
		)
		(fp_line
			(start -0.12065 -0.3048)
			(end -0.67945 -0.3048)
			(stroke
				(width 0.1)
				(type default)
			)
			(layer "B.Fab")
		)
		(fp_line
			(start 0.12065 -0.305054)
			(end 0.12065 -0.2794)
			(stroke
				(width 0.1)
				(type default)
			)
			(layer "B.Fab")
		)
		(fp_line
			(start 0.67945 -0.305054)
			(end 0.12065 -0.305054)
			(stroke
				(width 0.1)
				(type default)
			)
			(layer "B.Fab")
		)
		(pad "1" smd circle
			(at 0.40005 0 90)
			(size 0 0)
			(layers "B.Cu" "B.Mask" "B.Paste")
			(net "P3V3_AUX")
		)
		(pad "2" smd circle
			(at -0.40005 0 90)
			(size 0 0)
			(layers "B.Cu" "B.Mask" "B.Paste")
			(net "RST_ROT_CPU_N")
		)
	)
)
